# S9S_MB_2U (Grand Teton) — schematic netlist excerpt (pin names and nets, part order shuffled) for the footprints in the layout excerpt that follows; sources: Cadence DE-HDL packaged netlist, KiCad conversion of 03242023_DA0F0TMBIJ0_F0T_Motherboard_J_brd_V01_OCP.brd

R3188  Q_RES  33.2 1% CHIP  pkg 0402LF  page 161 : A = RST_OCP_V3_2_BUF_N ; B = RST_PERST2_OCP_V3_2_N
R3090  Q_RES  130 1% CHIP  pkg 0402LF  page 253 : A = LED_PWRGD_PVNN_MAIN_CPU0 ; B = P3V3_AUX

(kicad_pcb
	(version 20260206)
	(generator "pcbnew")
	(generator_version "10.0")
	(general
		(thickness 1.6)
		(legacy_teardrops no)
	)
	(paper "A4")
	(title_block
		(title "03242023_DA0F0TMBIJ0_F0T_Motherboard_J_brd_V01_OCP.brd")
		(comment 1 "Grand Teton / footprints 1290-1291 of 6105")
	)
	(layers
		(0 "F.Cu" signal "TOP")
		(4 "In1.Cu" signal "GND")
		(6 "In2.Cu" signal "IN1")
		(8 "In3.Cu" signal "GND1")
		(10 "In4.Cu" signal "IN2")
		(12 "In5.Cu" signal "GND2")
		(14 "In6.Cu" signal "IN3")
		(16 "In7.Cu" signal "GND3")
		(18 "In8.Cu" signal "VCC")
		(20 "In9.Cu" signal "VCC1")
		(22 "In10.Cu" signal "GND4")
		(24 "In11.Cu" signal "IN4")
		(26 "In12.Cu" signal "GND5")
		(28 "In13.Cu" signal "IN5")
		(30 "In14.Cu" signal "GND6")
		(32 "In15.Cu" signal "IN6")
		(34 "In16.Cu" signal "GND7")
		(2 "B.Cu" signal "BOTTOM")
		(9 "F.Adhes" user "F.Adhesive")
		(11 "B.Adhes" user "B.Adhesive")
		(13 "F.Paste" user "Package Geometry/Pastemask Top")
		(15 "B.Paste" user "Package Geometry/Pastemask Bottom")
		(5 "F.SilkS" user "Ref Des/Silkscreen Top")
		(7 "B.SilkS" user "Ref Des/Silkscreen Bottom")
		(1 "F.Mask" user "Board Geometry/Soldermask Top")
		(3 "B.Mask" user "Board Geometry/Soldermask Bottom")
		(17 "Dwgs.User" user "User.Drawings")
		(19 "Cmts.User" user "User.Comments")
		(21 "Eco1.User" user "User.Eco1")
		(23 "Eco2.User" user "User.Eco2")
		(25 "Edge.Cuts" user "Board Geometry/Outline")
		(27 "Margin" user)
		(31 "F.CrtYd" user "Package Geometry/Place Bound Top")
		(29 "B.CrtYd" user "Package Geometry/Place Bound Bottom")
		(35 "F.Fab" user "Ref Des/Assembly Top")
		(33 "B.Fab" user "Ref Des/Assembly Bottom")
	)
	(footprint ""
		(layer "F.Cu")
		(at 106.476038 -37.940742)
		(property "Reference" "R3188"
			(at 0 0 0)
			(layer "F.SilkS")
			(hide yes)
			(effects
				(font
					(size 1.27 1.27)
				)
			)
		)
		(property "Value" ""
			(at 0 0 0)
			(layer "F.Fab")
			(effects
				(font
					(size 1.27 1.27)
				)
			)
		)
		(duplicate_pad_numbers_are_jumpers no)
		(fp_line
			(start -0.7874 -0.4064)
			(end 0.7874 -0.4064)
			(stroke
				(width 0.1524)
				(type default)
			)
			(layer "F.SilkS")
		)
		(fp_line
			(start -0.7874 0.4064)
			(end -0.7874 -0.4064)
			(stroke
				(width 0.1524)
				(type default)
			)
			(layer "F.SilkS")
		)
		(fp_line
			(start 0.7874 -0.4064)
			(end 0.7874 0.4064)
			(stroke
				(width 0.1524)
				(type default)
			)
			(layer "F.SilkS")
		)
		(fp_line
			(start 0.7874 0.4064)
			(end -0.7874 0.4064)
			(stroke
				(width 0.1524)
				(type default)
			)
			(layer "F.SilkS")
		)
		(fp_line
			(start -0.67945 -0.305054)
			(end -0.12065 -0.305054)
			(stroke
				(width 0.1)
				(type default)
			)
			(layer "F.Fab")
		)
		(fp_line
			(start -0.67945 0.3048)
			(end -0.67945 -0.305054)
			(stroke
				(width 0.1)
				(type default)
			)
			(layer "F.Fab")
		)
		(fp_line
			(start -0.12065 -0.305054)
			(end -0.12065 -0.2794)
			(stroke
				(width 0.1)
				(type default)
			)
			(layer "F.Fab")
		)
		(fp_line
			(start -0.12065 -0.2794)
			(end 0.12065 -0.2794)
			(stroke
				(width 0.1)
				(type default)
			)
			(layer "F.Fab")
		)
		(fp_line
			(start -0.12065 0.2794)
			(end -0.12065 0.3048)
			(stroke
				(width 0.1)
				(type default)
			)
			(layer "F.Fab")
		)
		(fp_line
			(start -0.12065 0.3048)
			(end -0.67945 0.3048)
			(stroke
				(width 0.1)
				(type default)
			)
			(layer "F.Fab")
		)
		(fp_line
			(start 0.120396 0.2794)
			(end -0.12065 0.2794)
			(stroke
				(width 0.1)
				(type default)
			)
			(layer "F.Fab")
		)
		(fp_line
			(start 0.120396 0.3048)
			(end 0.120396 0.2794)
			(stroke
				(width 0.1)
				(type default)
			)
			(layer "F.Fab")
		)
		(fp_line
			(start 0.12065 -0.3048)
			(end 0.67945 -0.3048)
			(stroke
				(width 0.1)
				(type default)
			)
			(layer "F.Fab")
		)
		(fp_line
			(start 0.12065 -0.2794)
			(end 0.12065 -0.3048)
			(stroke
				(width 0.1)
				(type default)
			)
			(layer "F.Fab")
		)
		(fp_line
			(start 0.67945 -0.3048)
			(end 0.67945 0.3048)
			(stroke
				(width 0.1)
				(type default)
			)
			(layer "F.Fab")
		)
		(fp_line
			(start 0.67945 0.3048)
			(end 0.120396 0.3048)
			(stroke
				(width 0.1)
				(type default)
			)
			(layer "F.Fab")
		)
		(pad "1" smd circle
			(at -0.40005 0)
			(size 0 0)
			(layers "F.Cu" "F.Mask" "F.Paste")
			(net "RST_OCP_V3_2_BUF_N")
		)
		(pad "2" smd circle
			(at 0.40005 0)
			(size 0 0)
			(layers "F.Cu" "F.Mask" "F.Paste")
			(net "RST_PERST2_OCP_V3_2_N")
		)
	)
	(footprint ""
		(layer "F.Cu")
		(at 106.11231 -65.22212 -90)
		(property "Reference" "R3090"
			(at 0 0 270)
			(layer "F.SilkS")
			(hide yes)
			(effects
				(font
					(size 1.27 1.27)
				)
			)
		)
		(property "Value" ""
			(at 0 0 270)
			(layer "F.Fab")
			(effects
				(font
					(size 1.27 1.27)
				)
			)
		)
		(duplicate_pad_numbers_are_jumpers no)
		(fp_line
			(start -0.7874 0.4064)
			(end -0.7874 -0.4064)
			(stroke
				(width 0.1524)
				(type default)
			)
			(layer "F.SilkS")
		)
		(fp_line
			(start 0.7874 0.4064)
			(end -0.7874 0.4064)
			(stroke
				(width 0.1524)
				(type default)
			)
			(layer "F.SilkS")
		)
		(fp_line
			(start -0.7874 -0.4064)
			(end 0.7874 -0.4064)
			(stroke
				(width 0.1524)
				(type default)
			)
			(layer "F.SilkS")
		)
		(fp_line
			(start 0.7874 -0.4064)
			(end 0.7874 0.4064)
			(stroke
				(width 0.1524)
				(type default)
			)
			(layer "F.SilkS")
		)
		(fp_line
			(start -0.67945 0.3048)
			(end -0.67945 -0.305054)
			(stroke
				(width 0.1)
				(type default)
			)
			(layer "F.Fab")
		)
		(fp_line
			(start -0.12065 0.3048)
			(end -0.67945 0.3048)
			(stroke
				(width 0.1)
				(type default)
			)
			(layer "F.Fab")
		)
		(fp_line
			(start 0.120396 0.3048)
			(end 0.120396 0.2794)
			(stroke
				(width 0.1)
				(type default)
			)
			(layer "F.Fab")
		)
		(fp_line
			(start 0.67945 0.3048)
			(end 0.120396 0.3048)
			(stroke
				(width 0.1)
				(type default)
			)
			(layer "F.Fab")
		)
		(fp_line
			(start -0.12065 0.2794)
			(end -0.12065 0.3048)
			(stroke
				(width 0.1)
				(type default)
			)
			(layer "F.Fab")
		)
		(fp_line
			(start 0.120396 0.2794)
			(end -0.12065 0.2794)
			(stroke
				(width 0.1)
				(type default)
			)
			(layer "F.Fab")
		)
		(fp_line
			(start -0.12065 -0.2794)
			(end 0.12065 -0.2794)
			(stroke
				(width 0.1)
				(type default)
			)
			(layer "F.Fab")
		)
		(fp_line
			(start 0.12065 -0.2794)
			(end 0.12065 -0.3048)
			(stroke
				(width 0.1)
				(type default)
			)
			(layer "F.Fab")
		)
		(fp_line
			(start 0.12065 -0.3048)
			(end 0.67945 -0.3048)
			(stroke
				(width 0.1)
				(type default)
			)
			(layer "F.Fab")
		)
		(fp_line
			(start 0.67945 -0.3048)
			(end 0.67945 0.3048)
			(stroke
				(width 0.1)
				(type default)
			)
			(layer "F.Fab")
		)
		(fp_line
			(start -0.67945 -0.305054)
			(end -0.12065 -0.305054)
			(stroke
				(width 0.1)
				(type default)
			)
			(layer "F.Fab")
		)
		(fp_line
			(start -0.12065 -0.305054)
			(end -0.12065 -0.2794)
			(stroke
				(width 0.1)
				(type default)
			)
			(layer "F.Fab")
		)
		(pad "1" smd circle
			(at -0.40005 0 270)
			(size 0 0)
			(layers "F.Cu" "F.Mask" "F.Paste")
			(net "LED_PWRGD_PVNN_MAIN_CPU0")
		)
		(pad "2" smd circle
			(at 0.40005 0 270)
			(size 0 0)
			(layers "F.Cu" "F.Mask" "F.Paste")
			(net "P3V3_AUX")
		)
	)
)
